(kicad_pcb
	(version 20260206)
	(generator "pcbnew")
	(generator_version "10.0")
	(general
		(thickness 1.6)
		(legacy_teardrops no)
	)
	(paper "A4")
	(title_block
		(title "04192023_DAF0TMB3IC0_F0TG_MB_C_brd_V02_OCP.brd")
		(comment 1 "Grand Teton / footprints 920-926 of 8354")
	)
	(layers
		(0 "F.Cu" signal "TOP")
		(4 "In1.Cu" signal "GND")
		(6 "In2.Cu" signal "IN1")
		(8 "In3.Cu" signal "GND1")
		(10 "In4.Cu" signal "IN2")
		(12 "In5.Cu" signal "GND2")
		(14 "In6.Cu" signal "IN3")
		(16 "In7.Cu" signal "GND3")
		(18 "In8.Cu" signal "VCC")
		(20 "In9.Cu" signal "VCC1")
		(22 "In10.Cu" signal "GND4")
		(24 "In11.Cu" signal "IN4")
		(26 "In12.Cu" signal "GND5")
		(28 "In13.Cu" signal "IN5")
		(30 "In14.Cu" signal "GND6")
		(32 "In15.Cu" signal "IN6")
		(34 "In16.Cu" signal "GND7")
		(2 "B.Cu" signal "BOTTOM")
		(9 "F.Adhes" user "F.Adhesive")
		(11 "B.Adhes" user "B.Adhesive")
		(13 "F.Paste" user "Package Geometry/Pastemask Top")
		(15 "B.Paste" user "Package Geometry/Pastemask Bottom")
		(5 "F.SilkS" user "Ref Des/Silkscreen Top")
		(7 "B.SilkS" user "Ref Des/Silkscreen Bottom")
		(1 "F.Mask" user "Board Geometry/Soldermask Top")
		(3 "B.Mask" user "Board Geometry/Soldermask Bottom")
		(17 "Dwgs.User" user "User.Drawings")
		(19 "Cmts.User" user "User.Comments")
		(21 "Eco1.User" user "User.Eco1")
		(23 "Eco2.User" user "User.Eco2")
		(25 "Edge.Cuts" user "Board Geometry/Outline")
		(27 "Margin" user)
		(31 "F.CrtYd" user "Package Geometry/Place Bound Top")
		(29 "B.CrtYd" user "Package Geometry/Place Bound Bottom")
		(35 "F.Fab" user "Ref Des/Assembly Top")
		(33 "B.Fab" user "Ref Des/Assembly Bottom")
	)
	(footprint ""
		(layer "F.Cu")
		(at 319.940178 -47.002954)
		(property "Reference" "C2046"
			(at 0 0 0)
			(layer "F.SilkS")
			(hide yes)
			(effects
				(font
					(size 1.27 1.27)
				)
			)
		)
		(property "Value" ""
			(at 0 0 0)
			(layer "F.Fab")
			(effects
				(font
					(size 1.27 1.27)
				)
			)
		)
		(duplicate_pad_numbers_are_jumpers no)
		(fp_line
			(start -0.7874 -0.4064)
			(end 0.7874 -0.4064)
			(stroke
				(width 0.1524)
				(type default)
			)
			(layer "F.SilkS")
		)
		(fp_line
			(start -0.7874 0.4064)
			(end -0.7874 -0.4064)
			(stroke
				(width 0.1524)
				(type default)
			)
			(layer "F.SilkS")
		)
		(fp_line
			(start 0.7874 -0.4064)
			(end 0.7874 0.4064)
			(stroke
				(width 0.1524)
				(type default)
			)
			(layer "F.SilkS")
		)
		(fp_line
			(start 0.7874 0.4064)
			(end -0.7874 0.4064)
			(stroke
				(width 0.1524)
				(type default)
			)
			(layer "F.SilkS")
		)
		(fp_line
			(start -0.67945 -0.305054)
			(end -0.12065 -0.305054)
			(stroke
				(width 0.1)
				(type default)
			)
			(layer "F.Fab")
		)
		(fp_line
			(start -0.67945 0.3048)
			(end -0.67945 -0.305054)
			(stroke
				(width 0.1)
				(type default)
			)
			(layer "F.Fab")
		)
		(fp_line
			(start -0.12065 -0.305054)
			(end -0.12065 -0.2794)
			(stroke
				(width 0.1)
				(type default)
			)
			(layer "F.Fab")
		)
		(fp_line
			(start -0.12065 -0.2794)
			(end 0.12065 -0.2794)
			(stroke
				(width 0.1)
				(type default)
			)
			(layer "F.Fab")
		)
		(fp_line
			(start -0.12065 0.2794)
			(end -0.12065 0.3048)
			(stroke
				(width 0.1)
				(type default)
			)
			(layer "F.Fab")
		)
		(fp_line
			(start -0.12065 0.3048)
			(end -0.67945 0.3048)
			(stroke
				(width 0.1)
				(type default)
			)
			(layer "F.Fab")
		)
		(fp_line
			(start 0.120396 0.2794)
			(end -0.12065 0.2794)
			(stroke
				(width 0.1)
				(type default)
			)
			(layer "F.Fab")
		)
		(fp_line
			(start 0.120396 0.3048)
			(end 0.120396 0.2794)
			(stroke
				(width 0.1)
				(type default)
			)
			(layer "F.Fab")
		)
		(fp_line
			(start 0.12065 -0.3048)
			(end 0.67945 -0.3048)
			(stroke
				(width 0.1)
				(type default)
			)
			(layer "F.Fab")
		)
		(fp_line
			(start 0.12065 -0.2794)
			(end 0.12065 -0.3048)
			(stroke
				(width 0.1)
				(type default)
			)
			(layer "F.Fab")
		)
		(fp_line
			(start 0.67945 -0.3048)
			(end 0.67945 0.3048)
			(stroke
				(width 0.1)
				(type default)
			)
			(layer "F.Fab")
		)
		(fp_line
			(start 0.67945 0.3048)
			(end 0.120396 0.3048)
			(stroke
				(width 0.1)
				(type default)
			)
			(layer "F.Fab")
		)
		(pad "1" smd circle
			(at -0.40005 0)
			(size 0 0)
			(layers "F.Cu" "F.Mask" "F.Paste")
			(net "P12V_AUX_ADC_TIC")
		)
		(pad "2" smd circle
			(at 0.40005 0)
			(size 0 0)
			(layers "F.Cu" "F.Mask" "F.Paste")
			(net "GND")
		)
	)
	(footprint ""
		(layer "F.Cu")
		(at 31.712662 -421.916098 180)
		(property "Reference" "C1863"
			(at 0 0 180)
			(layer "F.SilkS")
			(hide yes)
			(effects
				(font
					(size 1.27 1.27)
				)
			)
		)
		(property "Value" ""
			(at 0 0 180)
			(layer "F.Fab")
			(effects
				(font
					(size 1.27 1.27)
				)
			)
		)
		(duplicate_pad_numbers_are_jumpers no)
		(fp_line
			(start 0.7874 0.4064)
			(end -0.7874 0.4064)
			(stroke
				(width 0.1524)
				(type default)
			)
			(layer "F.SilkS")
		)
		(fp_line
			(start 0.7874 -0.4064)
			(end 0.7874 0.4064)
			(stroke
				(width 0.1524)
				(type default)
			)
			(layer "F.SilkS")
		)
		(fp_line
			(start -0.7874 0.4064)
			(end -0.7874 -0.4064)
			(stroke
				(width 0.1524)
				(type default)
			)
			(layer "F.SilkS")
		)
		(fp_line
			(start -0.7874 -0.4064)
			(end 0.7874 -0.4064)
			(stroke
				(width 0.1524)
				(type default)
			)
			(layer "F.SilkS")
		)
		(fp_line
			(start 0.67945 0.3048)
			(end 0.120396 0.3048)
			(stroke
				(width 0.1)
				(type default)
			)
			(layer "F.Fab")
		)
		(fp_line
			(start 0.67945 -0.3048)
			(end 0.67945 0.3048)
			(stroke
				(width 0.1)
				(type default)
			)
			(layer "F.Fab")
		)
		(fp_line
			(start 0.12065 -0.2794)
			(end 0.12065 -0.3048)
			(stroke
				(width 0.1)
				(type default)
			)
			(layer "F.Fab")
		)
		(fp_line
			(start 0.12065 -0.3048)
			(end 0.67945 -0.3048)
			(stroke
				(width 0.1)
				(type default)
			)
			(layer "F.Fab")
		)
		(fp_line
			(start 0.120396 0.3048)
			(end 0.120396 0.2794)
			(stroke
				(width 0.1)
				(type default)
			)
			(layer "F.Fab")
		)
		(fp_line
			(start 0.120396 0.2794)
			(end -0.12065 0.2794)
			(stroke
				(width 0.1)
				(type default)
			)
			(layer "F.Fab")
		)
		(fp_line
			(start -0.12065 0.3048)
			(end -0.67945 0.3048)
			(stroke
				(width 0.1)
				(type default)
			)
			(layer "F.Fab")
		)
		(fp_line
			(start -0.12065 0.2794)
			(end -0.12065 0.3048)
			(stroke
				(width 0.1)
				(type default)
			)
			(layer "F.Fab")
		)
		(fp_line
			(start -0.12065 -0.2794)
			(end 0.12065 -0.2794)
			(stroke
				(width 0.1)
				(type default)
			)
			(layer "F.Fab")
		)
		(fp_line
			(start -0.12065 -0.305054)
			(end -0.12065 -0.2794)
			(stroke
				(width 0.1)
				(type default)
			)
			(layer "F.Fab")
		)
		(fp_line
			(start -0.67945 0.3048)
			(end -0.67945 -0.305054)
			(stroke
				(width 0.1)
				(type default)
			)
			(layer "F.Fab")
		)
		(fp_line
			(start -0.67945 -0.305054)
			(end -0.12065 -0.305054)
			(stroke
				(width 0.1)
				(type default)
			)
			(layer "F.Fab")
		)
		(pad "1" smd circle
			(at -0.40005 0 180)
			(size 0 0)
			(layers "F.Cu" "F.Mask" "F.Paste")
			(net "P3V3_AUX")
		)
		(pad "2" smd circle
			(at 0.40005 0 180)
			(size 0 0)
			(layers "F.Cu" "F.Mask" "F.Paste")
			(net "GND")
		)
	)
	(footprint ""
		(layer "F.Cu")
		(at 84.026502 -370.57203 -90)
		(property "Reference" "C729"
			(at 0 0 270)
			(layer "F.SilkS")
			(hide yes)
			(effects
				(font
					(size 1.27 1.27)
				)
			)
		)
		(property "Value" ""
			(at 0 0 270)
			(layer "F.Fab")
			(effects
				(font
					(size 1.27 1.27)
				)
			)
		)
		(duplicate_pad_numbers_are_jumpers no)
		(fp_line
			(start -0.299974 0.150114)
			(end -0.299974 -0.150114)
			(stroke
				(width 0.1)
				(type default)
			)
			(layer "F.Fab")
		)
		(fp_line
			(start 0.299974 0.150114)
			(end -0.299974 0.150114)
			(stroke
				(width 0.1)
				(type default)
			)
			(layer "F.Fab")
		)
		(fp_line
			(start -0.299974 -0.150114)
			(end 0.299974 -0.150114)
			(stroke
				(width 0.1)
				(type default)
			)
			(layer "F.Fab")
		)
		(fp_line
			(start 0.299974 -0.150114)
			(end 0.299974 0.150114)
			(stroke
				(width 0.1)
				(type default)
			)
			(layer "F.Fab")
		)
		(pad "1" smd rect
			(at -0.2667 0 270)
			(size 0.3048 0.381)
			(layers "F.Cu" "F.Mask" "F.Paste")
			(net "P5E_CPU1_P1_TX_C_DP<6>")
		)
		(pad "2" smd rect
			(at 0.2667 0 270)
			(size 0.3048 0.381)
			(layers "F.Cu" "F.Mask" "F.Paste")
			(net "P5E_CPU1_P1_TX_DP<6>")
		)
	)
	(footprint ""
		(layer "F.Cu")
		(at 104.389936 -127.768096 -90)
		(property "Reference" "R1452"
			(at 0 0 270)
			(layer "F.SilkS")
			(hide yes)
			(effects
				(font
					(size 1.27 1.27)
				)
			)
		)
		(property "Value" ""
			(at 0 0 270)
			(layer "F.Fab")
			(effects
				(font
					(size 1.27 1.27)
				)
			)
		)
		(duplicate_pad_numbers_are_jumpers no)
		(fp_line
			(start -0.7874 0.4064)
			(end -0.7874 -0.4064)
			(stroke
				(width 0.1524)
				(type default)
			)
			(layer "F.SilkS")
		)
		(fp_line
			(start 0.7874 0.4064)
			(end -0.7874 0.4064)
			(stroke
				(width 0.1524)
				(type default)
			)
			(layer "F.SilkS")
		)
		(fp_line
			(start -0.7874 -0.4064)
			(end 0.7874 -0.4064)
			(stroke
				(width 0.1524)
				(type default)
			)
			(layer "F.SilkS")
		)
		(fp_line
			(start 0.7874 -0.4064)
			(end 0.7874 0.4064)
			(stroke
				(width 0.1524)
				(type default)
			)
			(layer "F.SilkS")
		)
		(fp_line
			(start -0.67945 0.3048)
			(end -0.67945 -0.305054)
			(stroke
				(width 0.1)
				(type default)
			)
			(layer "F.Fab")
		)
		(fp_line
			(start -0.12065 0.3048)
			(end -0.67945 0.3048)
			(stroke
				(width 0.1)
				(type default)
			)
			(layer "F.Fab")
		)
		(fp_line
			(start 0.120396 0.3048)
			(end 0.120396 0.2794)
			(stroke
				(width 0.1)
				(type default)
			)
			(layer "F.Fab")
		)
		(fp_line
			(start 0.67945 0.3048)
			(end 0.120396 0.3048)
			(stroke
				(width 0.1)
				(type default)
			)
			(layer "F.Fab")
		)
		(fp_line
			(start -0.12065 0.2794)
			(end -0.12065 0.3048)
			(stroke
				(width 0.1)
				(type default)
			)
			(layer "F.Fab")
		)
		(fp_line
			(start 0.120396 0.2794)
			(end -0.12065 0.2794)
			(stroke
				(width 0.1)
				(type default)
			)
			(layer "F.Fab")
		)
		(fp_line
			(start -0.12065 -0.2794)
			(end 0.12065 -0.2794)
			(stroke
				(width 0.1)
				(type default)
			)
			(layer "F.Fab")
		)
		(fp_line
			(start 0.12065 -0.2794)
			(end 0.12065 -0.3048)
			(stroke
				(width 0.1)
				(type default)
			)
			(layer "F.Fab")
		)
		(fp_line
			(start 0.12065 -0.3048)
			(end 0.67945 -0.3048)
			(stroke
				(width 0.1)
				(type default)
			)
			(layer "F.Fab")
		)
		(fp_line
			(start 0.67945 -0.3048)
			(end 0.67945 0.3048)
			(stroke
				(width 0.1)
				(type default)
			)
			(layer "F.Fab")
		)
		(fp_line
			(start -0.67945 -0.305054)
			(end -0.12065 -0.305054)
			(stroke
				(width 0.1)
				(type default)
			)
			(layer "F.Fab")
		)
		(fp_line
			(start -0.12065 -0.305054)
			(end -0.12065 -0.2794)
			(stroke
				(width 0.1)
				(type default)
			)
			(layer "F.Fab")
		)
		(pad "1" smd circle
			(at -0.40005 0 270)
			(size 0 0)
			(layers "F.Cu" "F.Mask" "F.Paste")
			(net "P1V8_AUX")
		)
		(pad "2" smd circle
			(at 0.40005 0 270)
			(size 0 0)
			(layers "F.Cu" "F.Mask" "F.Paste")
			(net "PWRGD_P12V_MEM_CPU1")
		)
	)
	(footprint ""
		(layer "F.Cu")
		(at 226.421442 -315.82868 90)
		(property "Reference" "PC6804"
			(at -1.75768 -4.906772 90)
			(unlocked yes)
			(layer "F.SilkS")
			(effects
				(font
					(size 0.7874 0.5842)
					(thickness 0.1524)
				)
				(justify left)
			)
		)
		(property "Value" ""
			(at 0 0 90)
			(layer "F.Fab")
			(effects
				(font
					(size 1.27 1.27)
				)
			)
		)
		(duplicate_pad_numbers_are_jumpers no)
		(fp_line
			(start 2.750058 -2.750058)
			(end -1.988058 -2.750058)
			(stroke
				(width 0.1524)
				(type default)
			)
			(layer "F.SilkS")
		)
		(fp_line
			(start -1.988058 -2.750058)
			(end -2.750058 -1.988058)
			(stroke
				(width 0.1524)
				(type default)
			)
			(layer "F.SilkS")
		)
		(fp_line
			(start -2.750058 -1.988058)
			(end -2.750058 -0.9398)
			(stroke
				(width 0.1524)
				(type default)
			)
			(layer "F.SilkS")
		)
		(fp_line
			(start 2.750058 -0.9398)
			(end 2.750058 -2.750058)
			(stroke
				(width 0.1524)
				(type default)
			)
			(layer "F.SilkS")
		)
		(fp_line
			(start -2.750058 0.9398)
			(end -2.750058 1.988058)
			(stroke
				(width 0.1524)
				(type default)
			)
			(layer "F.SilkS")
		)
		(fp_line
			(start -2.750058 1.988058)
			(end -1.988058 2.750058)
			(stroke
				(width 0.1524)
				(type default)
			)
			(layer "F.SilkS")
		)
		(fp_line
			(start 2.750058 2.750058)
			(end 2.750058 0.9398)
			(stroke
				(width 0.1524)
				(type default)
			)
			(layer "F.SilkS")
		)
		(fp_line
			(start -1.988058 2.750058)
			(end 2.750058 2.750058)
			(stroke
				(width 0.1524)
				(type default)
			)
			(layer "F.SilkS")
		)
		(fp_line
			(start 2.750058 -2.750058)
			(end -2.750058 -2.750058)
			(stroke
				(width 0.1)
				(type default)
			)
			(layer "F.Fab")
		)
		(fp_line
			(start -2.750058 -2.750058)
			(end -2.750058 2.750058)
			(stroke
				(width 0.1)
				(type default)
			)
			(layer "F.Fab")
		)
		(fp_line
			(start 2.750058 2.750058)
			(end 2.750058 -2.750058)
			(stroke
				(width 0.1)
				(type default)
			)
			(layer "F.Fab")
		)
		(fp_line
			(start -2.750058 2.750058)
			(end 2.750058 2.750058)
			(stroke
				(width 0.1)
				(type default)
			)
			(layer "F.Fab")
		)
		(pad "1" smd rect
			(at -2.199894 0 180)
			(size 1.6002 3.0226)
			(layers "F.Cu" "F.Mask" "F.Paste")
			(net "P1V8_CPU1_RT_1D")
		)
		(pad "2" smd rect
			(at 2.199894 0 180)
			(size 1.6002 3.0226)
			(layers "F.Cu" "F.Mask" "F.Paste")
			(net "GND")
		)
	)
	(footprint ""
		(layer "F.Cu")
		(at 72.274684 -408.517344 -90)
		(property "Reference" "C6646"
			(at 0 0 270)
			(layer "F.SilkS")
			(hide yes)
			(effects
				(font
					(size 1.27 1.27)
				)
			)
		)
		(property "Value" ""
			(at 0 0 270)
			(layer "F.Fab")
			(effects
				(font
					(size 1.27 1.27)
				)
			)
		)
		(duplicate_pad_numbers_are_jumpers no)
		(fp_line
			(start -0.299974 0.150114)
			(end -0.299974 -0.150114)
			(stroke
				(width 0.1)
				(type default)
			)
			(layer "F.Fab")
		)
		(fp_line
			(start 0.299974 0.150114)
			(end -0.299974 0.150114)
			(stroke
				(width 0.1)
				(type default)
			)
			(layer "F.Fab")
		)
		(fp_line
			(start -0.299974 -0.150114)
			(end 0.299974 -0.150114)
			(stroke
				(width 0.1)
				(type default)
			)
			(layer "F.Fab")
		)
		(fp_line
			(start 0.299974 -0.150114)
			(end 0.299974 0.150114)
			(stroke
				(width 0.1)
				(type default)
			)
			(layer "F.Fab")
		)
		(pad "1" smd rect
			(at -0.2667 0 270)
			(size 0.3048 0.381)
			(layers "F.Cu" "F.Mask" "F.Paste")
			(net "P5E_CPU1_P0_TX_BUF_C_DN<8>")
		)
		(pad "2" smd rect
			(at 0.2667 0 270)
			(size 0.3048 0.381)
			(layers "F.Cu" "F.Mask" "F.Paste")
			(net "P5E_CPU1_P0_TX_BUF_DN<8>")
		)
	)
	(footprint ""
		(layer "F.Cu")
		(at 57.17794 -346.87129 -90)
		(property "Reference" "PC440_1"
			(at 0 0 270)
			(layer "F.SilkS")
			(hide yes)
			(effects
				(font
					(size 1.27 1.27)
				)
			)
		)
		(property "Value" ""
			(at 0 0 270)
			(layer "F.Fab")
			(effects
				(font
					(size 1.27 1.27)
				)
			)
		)
		(duplicate_pad_numbers_are_jumpers no)
		(fp_line
			(start -0.7874 0.4064)
			(end -0.7874 -0.4064)
			(stroke
				(width 0.1524)
				(type default)
			)
			(layer "F.SilkS")
		)
		(fp_line
			(start 0.7874 0.4064)
			(end -0.7874 0.4064)
			(stroke
				(width 0.1524)
				(type default)
			)
			(layer "F.SilkS")
		)
		(fp_line
			(start -0.7874 -0.4064)
			(end 0.7874 -0.4064)
			(stroke
				(width 0.1524)
				(type default)
			)
			(layer "F.SilkS")
		)
		(fp_line
			(start 0.7874 -0.4064)
			(end 0.7874 0.4064)
			(stroke
				(width 0.1524)
				(type default)
			)
			(layer "F.SilkS")
		)
		(fp_line
			(start -0.67945 0.3048)
			(end -0.67945 -0.305054)
			(stroke
				(width 0.1)
				(type default)
			)
			(layer "F.Fab")
		)
		(fp_line
			(start -0.12065 0.3048)
			(end -0.67945 0.3048)
			(stroke
				(width 0.1)
				(type default)
			)
			(layer "F.Fab")
		)
		(fp_line
			(start 0.120396 0.3048)
			(end 0.120396 0.2794)
			(stroke
				(width 0.1)
				(type default)
			)
			(layer "F.Fab")
		)
		(fp_line
			(start 0.67945 0.3048)
			(end 0.120396 0.3048)
			(stroke
				(width 0.1)
				(type default)
			)
			(layer "F.Fab")
		)
		(fp_line
			(start -0.12065 0.2794)
			(end -0.12065 0.3048)
			(stroke
				(width 0.1)
				(type default)
			)
			(layer "F.Fab")
		)
		(fp_line
			(start 0.120396 0.2794)
			(end -0.12065 0.2794)
			(stroke
				(width 0.1)
				(type default)
			)
			(layer "F.Fab")
		)
		(fp_line
			(start -0.12065 -0.2794)
			(end 0.12065 -0.2794)
			(stroke
				(width 0.1)
				(type default)
			)
			(layer "F.Fab")
		)
		(fp_line
			(start 0.12065 -0.2794)
			(end 0.12065 -0.3048)
			(stroke
				(width 0.1)
				(type default)
			)
			(layer "F.Fab")
		)
		(fp_line
			(start 0.12065 -0.3048)
			(end 0.67945 -0.3048)
			(stroke
				(width 0.1)
				(type default)
			)
			(layer "F.Fab")
		)
		(fp_line
			(start 0.67945 -0.3048)
			(end 0.67945 0.3048)
			(stroke
				(width 0.1)
				(type default)
			)
			(layer "F.Fab")
		)
		(fp_line
			(start -0.67945 -0.305054)
			(end -0.12065 -0.305054)
			(stroke
				(width 0.1)
				(type default)
			)
			(layer "F.Fab")
		)
		(fp_line
			(start -0.12065 -0.305054)
			(end -0.12065 -0.2794)
			(stroke
				(width 0.1)
				(type default)
			)
			(layer "F.Fab")
		)
		(pad "1" smd circle
			(at -0.40005 0 270)
			(size 0 0)
			(layers "F.Cu" "F.Mask" "F.Paste")
			(net "SW_P12V_AUX_PVDDIO_P1_FLT")
		)
		(pad "2" smd circle
			(at 0.40005 0 270)
			(size 0 0)
			(layers "F.Cu" "F.Mask" "F.Paste")
			(net "GND")
		)
	)
)
